# S9S_MB_2U (Grand Teton) — schematic netlist excerpt (pin names and nets, part order shuffled) for the footprints in the layout excerpt that follows; sources: Cadence DE-HDL packaged netlist, KiCad conversion of 03242023_DA0F0TMBIJ0_F0T_Motherboard_J_brd_V01_OCP.brd

R4534  Q_RES  0 5% CHIP  pkg 0402LF  page 206 : A = CLK_SWB_OE_N ; B = FM_DB2000_8_OE_N

X5  TP_TDR_4P_FTS  TP_TDR_4P_DIP EMPTY  pkg TH  page 309
  S1  = TDR_DIFF_85_IN4_DP
  P1  = T1_GND
  P2  = T1_GND
  S2  = TDR_DIFF_85_IN4_DN

(kicad_pcb
	(version 20260206)
	(generator "pcbnew")
	(generator_version "10.0")
	(general
		(thickness 1.6)
		(legacy_teardrops no)
	)
	(paper "A4")
	(title_block
		(title "03242023_DA0F0TMBIJ0_F0T_Motherboard_J_brd_V01_OCP.brd")
		(comment 1 "Grand Teton / footprints 4929-4930 of 6105")
	)
	(layers
		(0 "F.Cu" signal "TOP")
		(4 "In1.Cu" signal "GND")
		(6 "In2.Cu" signal "IN1")
		(8 "In3.Cu" signal "GND1")
		(10 "In4.Cu" signal "IN2")
		(12 "In5.Cu" signal "GND2")
		(14 "In6.Cu" signal "IN3")
		(16 "In7.Cu" signal "GND3")
		(18 "In8.Cu" signal "VCC")
		(20 "In9.Cu" signal "VCC1")
		(22 "In10.Cu" signal "GND4")
		(24 "In11.Cu" signal "IN4")
		(26 "In12.Cu" signal "GND5")
		(28 "In13.Cu" signal "IN5")
		(30 "In14.Cu" signal "GND6")
		(32 "In15.Cu" signal "IN6")
		(34 "In16.Cu" signal "GND7")
		(2 "B.Cu" signal "BOTTOM")
		(9 "F.Adhes" user "F.Adhesive")
		(11 "B.Adhes" user "B.Adhesive")
		(13 "F.Paste" user "Package Geometry/Pastemask Top")
		(15 "B.Paste" user "Package Geometry/Pastemask Bottom")
		(5 "F.SilkS" user "Ref Des/Silkscreen Top")
		(7 "B.SilkS" user "Ref Des/Silkscreen Bottom")
		(1 "F.Mask" user "Board Geometry/Soldermask Top")
		(3 "B.Mask" user "Board Geometry/Soldermask Bottom")
		(17 "Dwgs.User" user "User.Drawings")
		(19 "Cmts.User" user "User.Comments")
		(21 "Eco1.User" user "User.Eco1")
		(23 "Eco2.User" user "User.Eco2")
		(25 "Edge.Cuts" user "Board Geometry/Outline")
		(27 "Margin" user)
		(31 "F.CrtYd" user "Package Geometry/Place Bound Top")
		(29 "B.CrtYd" user "Package Geometry/Place Bound Bottom")
		(35 "F.Fab" user "Ref Des/Assembly Top")
		(33 "B.Fab" user "Ref Des/Assembly Bottom")
	)
	(footprint ""
		(layer "B.Cu")
		(at 520.044426 -153.203148 90)
		(property "Reference" "X5"
			(at 1.4732 2.650998 270)
			(unlocked yes)
			(layer "B.SilkS")
			(effects
				(font
					(size 0.7874 0.5842)
					(thickness 0.1524)
				)
				(justify left mirror)
			)
		)
		(property "Value" ""
			(at 0 0 90)
			(layer "B.Fab")
			(effects
				(font
					(size 1.27 1.27)
				)
				(justify mirror)
			)
		)
		(property "Device Type" "TP_TDR_4P_FTS_TH-TP_TDR_4P_DIPA"
			(at -1.30175 1.27 0)
			(unlocked yes)
			(layer "B.Fab")
			(hide yes)
			(effects
				(font
					(size 0.635 0.4064)
					(thickness 0.1524)
				)
				(justify mirror)
			)
		)
		(property "User Part Number" "N_A"
			(at -1.30175 1.27 0)
			(unlocked yes)
			(layer "Cmts.User")
			(hide yes)
			(effects
				(font
					(size 0.635 0.4064)
					(thickness 0.1524)
				)
				(justify mirror)
			)
		)
		(duplicate_pad_numbers_are_jumpers no)
		(fp_line
			(start 0 -1.27)
			(end 0 -0.635)
			(stroke
				(width 0.1524)
				(type default)
			)
			(layer "B.SilkS")
		)
		(fp_line
			(start -2.54 -1.27)
			(end 0 -1.27)
			(stroke
				(width 0.1524)
				(type default)
			)
			(layer "B.SilkS")
		)
		(fp_line
			(start -2.54 -1.1303)
			(end -2.54 -1.27)
			(stroke
				(width 0.1524)
				(type default)
			)
			(layer "B.SilkS")
		)
		(fp_line
			(start 0 0.635)
			(end 0 1.905)
			(stroke
				(width 0.1524)
				(type default)
			)
			(layer "B.SilkS")
		)
		(fp_line
			(start -2.54 1.4097)
			(end -2.54 1.1303)
			(stroke
				(width 0.1524)
				(type default)
			)
			(layer "B.SilkS")
		)
		(fp_line
			(start 0 3.175)
			(end 0 3.81)
			(stroke
				(width 0.1524)
				(type default)
			)
			(layer "B.SilkS")
		)
		(fp_line
			(start 0 3.81)
			(end -2.54 3.81)
			(stroke
				(width 0.1524)
				(type default)
			)
			(layer "B.SilkS")
		)
		(fp_line
			(start -2.54 3.81)
			(end -2.54 3.6703)
			(stroke
				(width 0.1524)
				(type default)
			)
			(layer "B.SilkS")
		)
		(fp_poly
			(pts
				(xy 2.76987 -0.972566) (xy 2.76987 0.551434) (xy 1.24587 -0.210566)
			)
			(stroke
				(width 0)
				(type default)
			)
			(fill yes)
			(layer "B.SilkS")
		)
		(fp_line
			(start 0 -1.27)
			(end 0 3.81)
			(stroke
				(width 0.1)
				(type default)
			)
			(layer "B.Fab")
		)
		(fp_line
			(start -2.54 -1.27)
			(end 0 -1.27)
			(stroke
				(width 0.1)
				(type default)
			)
			(layer "B.Fab")
		)
		(fp_line
			(start 0 3.81)
			(end -2.54 3.81)
			(stroke
				(width 0.1)
				(type default)
			)
			(layer "B.Fab")
		)
		(fp_line
			(start -2.54 3.81)
			(end -2.54 -1.27)
			(stroke
				(width 0.1)
				(type default)
			)
			(layer "B.Fab")
		)
		(fp_poly
			(pts
				(xy 0.761746 0) (xy 2.285746 -0.762) (xy 2.285746 0.762)
			)
			(stroke
				(width 0)
				(type default)
			)
			(fill yes)
			(layer "B.Fab")
		)
		(pad "1" thru_hole circle
			(at 0 0 270)
			(size 1.0033 1.0033)
			(drill 0.249936)
			(layers "*.Cu" "*.Mask")
			(remove_unused_layers no)
			(net "TDR_DIFF_85_IN4_DP")
			(clearance 0.10795)
			(padstack
				(mode front_inner_back)
				(layer "Inner"
					(shape circle)
					(size 0.8001 0.8001)
					(clearance 0.1524)
				)
				(layer "B.Cu"
					(shape circle)
					(size 1.0033 1.0033)
					(thermal_gap 0.10795)
					(clearance 0.10795)
				)
			)
		)
		(pad "2" thru_hole circle
			(at -2.54 0 270)
			(size 1.9939 1.9939)
			(drill 0.249936)
			(layers "*.Cu" "*.Mask")
			(remove_unused_layers no)
			(net "T1_GND")
			(clearance 0.10795)
			(padstack
				(mode front_inner_back)
				(layer "Inner"
					(shape circle)
					(size 0.8001 0.8001)
					(clearance 0.1524)
				)
				(layer "B.Cu"
					(shape circle)
					(size 1.9939 1.9939)
					(thermal_gap 0.10795)
					(clearance 0.10795)
				)
			)
		)
		(pad "3" thru_hole circle
			(at -2.54 2.54 270)
			(size 1.9939 1.9939)
			(drill 0.249936)
			(layers "*.Cu" "*.Mask")
			(remove_unused_layers no)
			(net "T1_GND")
			(clearance 0.10795)
			(padstack
				(mode front_inner_back)
				(layer "Inner"
					(shape circle)
					(size 0.8001 0.8001)
					(clearance 0.1524)
				)
				(layer "B.Cu"
					(shape circle)
					(size 1.9939 1.9939)
					(thermal_gap 0.10795)
					(clearance 0.10795)
				)
			)
		)
		(pad "4" thru_hole circle
			(at 0 2.54 270)
			(size 1.0033 1.0033)
			(drill 0.249936)
			(layers "*.Cu" "*.Mask")
			(remove_unused_layers no)
			(net "TDR_DIFF_85_IN4_DN")
			(clearance 0.10795)
			(padstack
				(mode front_inner_back)
				(layer "Inner"
					(shape circle)
					(size 0.8001 0.8001)
					(clearance 0.1524)
				)
				(layer "B.Cu"
					(shape circle)
					(size 1.0033 1.0033)
					(thermal_gap 0.10795)
					(clearance 0.10795)
				)
			)
		)
	)
	(footprint ""
		(layer "B.Cu")
		(at 229.89032 -127.922274 180)
		(property "Reference" "R4534"
			(at 0 0 0)
			(layer "B.SilkS")
			(hide yes)
			(effects
				(font
					(size 1.27 1.27)
				)
				(justify mirror)
			)
		)
		(property "Value" ""
			(at 0 0 0)
			(layer "B.Fab")
			(effects
				(font
					(size 1.27 1.27)
				)
				(justify mirror)
			)
		)
		(duplicate_pad_numbers_are_jumpers no)
		(fp_line
			(start 0.7874 0.4064)
			(end 0.7874 -0.4064)
			(stroke
				(width 0.1524)
				(type default)
			)
			(layer "B.SilkS")
		)
		(fp_line
			(start 0.7874 -0.4064)
			(end -0.7874 -0.4064)
			(stroke
				(width 0.1524)
				(type default)
			)
			(layer "B.SilkS")
		)
		(fp_line
			(start -0.7874 0.4064)
			(end 0.7874 0.4064)
			(stroke
				(width 0.1524)
				(type default)
			)
			(layer "B.SilkS")
		)
		(fp_line
			(start -0.7874 -0.4064)
			(end -0.7874 0.4064)
			(stroke
				(width 0.1524)
				(type default)
			)
			(layer "B.SilkS")
		)
		(fp_line
			(start 0.67945 0.3048)
			(end 0.67945 -0.305054)
			(stroke
				(width 0.1)
				(type default)
			)
			(layer "B.Fab")
		)
		(fp_line
			(start 0.67945 -0.305054)
			(end 0.12065 -0.305054)
			(stroke
				(width 0.1)
				(type default)
			)
			(layer "B.Fab")
		)
		(fp_line
			(start 0.12065 0.3048)
			(end 0.67945 0.3048)
			(stroke
				(width 0.1)
				(type default)
			)
			(layer "B.Fab")
		)
		(fp_line
			(start 0.12065 0.2794)
			(end 0.12065 0.3048)
			(stroke
				(width 0.1)
				(type default)
			)
			(layer "B.Fab")
		)
		(fp_line
			(start 0.12065 -0.2794)
			(end -0.12065 -0.2794)
			(stroke
				(width 0.1)
				(type default)
			)
			(layer "B.Fab")
		)
		(fp_line
			(start 0.12065 -0.305054)
			(end 0.12065 -0.2794)
			(stroke
				(width 0.1)
				(type default)
			)
			(layer "B.Fab")
		)
		(fp_line
			(start -0.120396 0.3048)
			(end -0.120396 0.2794)
			(stroke
				(width 0.1)
				(type default)
			)
			(layer "B.Fab")
		)
		(fp_line
			(start -0.120396 0.2794)
			(end 0.12065 0.2794)
			(stroke
				(width 0.1)
				(type default)
			)
			(layer "B.Fab")
		)
		(fp_line
			(start -0.12065 -0.2794)
			(end -0.12065 -0.3048)
			(stroke
				(width 0.1)
				(type default)
			)
			(layer "B.Fab")
		)
		(fp_line
			(start -0.12065 -0.3048)
			(end -0.67945 -0.3048)
			(stroke
				(width 0.1)
				(type default)
			)
			(layer "B.Fab")
		)
		(fp_line
			(start -0.67945 0.3048)
			(end -0.120396 0.3048)
			(stroke
				(width 0.1)
				(type default)
			)
			(layer "B.Fab")
		)
		(fp_line
			(start -0.67945 -0.3048)
			(end -0.67945 0.3048)
			(stroke
				(width 0.1)
				(type default)
			)
			(layer "B.Fab")
		)
		(pad "1" smd circle
			(at 0.40005 0)
			(size 0 0)
			(layers "B.Cu" "B.Mask" "B.Paste")
			(net "CLK_SWB_OE_N")
		)
		(pad "2" smd circle
			(at -0.40005 0)
			(size 0 0)
			(layers "B.Cu" "B.Mask" "B.Paste")
			(net "FM_DB2000_8_OE_N")
		)
	)
)
